(kicad_pcb
	(version 20260206)
	(generator "pcbnew")
	(generator_version "10.0")
	(general
		(thickness 1.6)
		(legacy_teardrops no)
	)
	(paper "A4")
	(title_block
		(title "panther-plus-userver — 13130-1b_20150205.brd")
		(comment 1 "Honey Badger (Wiwynn) / footprints 492-499 of 1509")
	)
	(layers
		(0 "F.Cu" signal "TOP")
		(4 "In1.Cu" signal "L2")
		(6 "In2.Cu" signal "L3")
		(8 "In3.Cu" signal "L4")
		(10 "In4.Cu" signal "L5")
		(12 "In5.Cu" signal "L6")
		(14 "In6.Cu" signal "L7")
		(16 "In7.Cu" signal "L8")
		(18 "In8.Cu" signal "L9")
		(20 "In9.Cu" signal "L10")
		(22 "In10.Cu" signal "L11")
		(2 "B.Cu" signal "BOTTOM")
		(9 "F.Adhes" user "F.Adhesive")
		(11 "B.Adhes" user "B.Adhesive")
		(13 "F.Paste" user "Package Geometry/Pastemask Top")
		(15 "B.Paste" user "Package Geometry/Pastemask Bottom")
		(5 "F.SilkS" user "Ref Des/Silkscreen Top")
		(7 "B.SilkS" user "Ref Des/Silkscreen Bottom")
		(1 "F.Mask" user "Board Geometry/Soldermask Top")
		(3 "B.Mask" user "Board Geometry/Soldermask Bottom")
		(17 "Dwgs.User" user "User.Drawings")
		(19 "Cmts.User" user "User.Comments")
		(21 "Eco1.User" user "User.Eco1")
		(23 "Eco2.User" user "User.Eco2")
		(25 "Edge.Cuts" user "Board Geometry/Outline")
		(27 "Margin" user)
		(31 "F.CrtYd" user "Package Geometry/Place Bound Top")
		(29 "B.CrtYd" user "Package Geometry/Place Bound Bottom")
		(35 "F.Fab" user "Ref Des/Assembly Top")
		(33 "B.Fab" user "Ref Des/Assembly Bottom")
	)
	(footprint ""
		(layer "F.Cu")
		(at 171.2468 -12.701778 180)
		(property "Reference" "C300"
			(at 0 0 180)
			(layer "F.SilkS")
			(hide yes)
			(effects
				(font
					(size 1.27 1.27)
				)
			)
		)
		(property "Value" "SC10U6D3V3MX-GP"
			(at -0.0254 -2.0193 180)
			(unlocked yes)
			(layer "F.Fab")
			(hide yes)
			(effects
				(font
					(size 1.016 1.016)
					(thickness 0.1524)
				)
			)
		)
		(property "Device Type" "C603H38"
			(at -0.0254 -3.5433 180)
			(unlocked yes)
			(layer "F.Fab")
			(hide yes)
			(effects
				(font
					(size 1.016 1.016)
					(thickness 0.1524)
				)
			)
		)
		(duplicate_pad_numbers_are_jumpers no)
		(fp_line
			(start -0.4064 0)
			(end 0.4064 0)
			(stroke
				(width 0.2286)
				(type default)
			)
			(layer "F.SilkS")
		)
		(fp_rect
			(start -0.635 1.1811)
			(end 0.635 -1.1811)
			(stroke
				(width 0)
				(type default)
			)
			(fill no)
			(layer "F.CrtYd")
		)
		(fp_rect
			(start -0.635 1.1811)
			(end 0.635 -1.1811)
			(stroke
				(width 0)
				(type default)
			)
			(fill no)
			(layer "F.Fab")
		)
		(pad "1" smd custom
			(at 0 -0.6604 180)
			(size 0.19685 0.19685)
			(layers "F.Cu" "F.Mask" "F.Paste")
			(net "PV_VDDR")
			(options
				(clearance outline)
				(anchor circle)
			)
			(primitives
				(gr_poly
					(pts
						(arc
							(start 0.508 -0.2921)
							(mid 0.478242 -0.363942)
							(end 0.4064 -0.3937)
						)
						(arc
							(start -0.4064 -0.3937)
							(mid -0.478242 -0.363942)
							(end -0.508 -0.2921)
						)
						(arc
							(start -0.508 0.2921)
							(mid -0.478242 0.363942)
							(end -0.4064 0.3937)
						)
						(arc
							(start 0.4064 0.3937)
							(mid 0.478242 0.363942)
							(end 0.508 0.2921)
						)
					)
					(width 0)
					(fill yes)
				)
			)
		)
		(pad "2" smd custom
			(at 0 0.6604 180)
			(size 0.19685 0.19685)
			(layers "F.Cu" "F.Mask" "F.Paste")
			(net "GND")
			(options
				(clearance outline)
				(anchor circle)
			)
			(primitives
				(gr_poly
					(pts
						(arc
							(start 0.508 -0.2921)
							(mid 0.478242 -0.363942)
							(end 0.4064 -0.3937)
						)
						(arc
							(start -0.4064 -0.3937)
							(mid -0.478242 -0.363942)
							(end -0.508 -0.2921)
						)
						(arc
							(start -0.508 0.2921)
							(mid -0.478242 0.363942)
							(end -0.4064 0.3937)
						)
						(arc
							(start 0.4064 0.3937)
							(mid 0.478242 0.363942)
							(end 0.508 0.2921)
						)
					)
					(width 0)
					(fill yes)
				)
			)
		)
	)
	(footprint ""
		(layer "F.Cu")
		(at 187.5028 -25.781 90)
		(property "Reference" "PR162"
			(at 0 0 90)
			(layer "F.SilkS")
			(hide yes)
			(effects
				(font
					(size 1.27 1.27)
				)
			)
		)
		(property "Value" "0R2J-2-GP"
			(at 1.7907 -1.1176 90)
			(unlocked yes)
			(layer "F.Fab")
			(hide yes)
			(effects
				(font
					(size 1.016 1.016)
					(thickness 0.1524)
				)
			)
		)
		(property "Device Type" "R402H16"
			(at 1.7907 -2.6416 90)
			(unlocked yes)
			(layer "F.Fab")
			(hide yes)
			(effects
				(font
					(size 1.016 1.016)
					(thickness 0.1524)
				)
			)
		)
		(duplicate_pad_numbers_are_jumpers no)
		(fp_rect
			(start -0.381 0.8382)
			(end 0.381 -0.8382)
			(stroke
				(width 0)
				(type default)
			)
			(fill no)
			(layer "F.CrtYd")
		)
		(fp_rect
			(start -0.381 0.8382)
			(end 0.381 -0.8382)
			(stroke
				(width 0)
				(type default)
			)
			(fill no)
			(layer "F.Fab")
		)
		(pad "1" smd custom
			(at 0 -0.4318 90)
			(size 0.127 0.127)
			(layers "F.Cu" "F.Mask" "F.Paste")
			(net "VSENSE_PVDDR_A_VSEN")
			(options
				(clearance outline)
				(anchor circle)
			)
			(primitives
				(gr_poly
					(pts
						(arc
							(start -0.2032 -0.2794)
							(mid -0.239121 -0.264521)
							(end -0.254 -0.2286)
						)
						(arc
							(start -0.254 0.2286)
							(mid -0.239121 0.264521)
							(end -0.2032 0.2794)
						)
						(arc
							(start 0.2032 0.2794)
							(mid 0.239121 0.264521)
							(end 0.254 0.2286)
						)
						(arc
							(start 0.254 -0.2286)
							(mid 0.239121 -0.264521)
							(end 0.2032 -0.2794)
						)
					)
					(width 0)
					(fill yes)
				)
			)
		)
		(pad "2" smd custom
			(at 0 0.4318 90)
			(size 0.127 0.127)
			(layers "F.Cu" "F.Mask" "F.Paste")
			(net "VR_PVDDR_A_VTT")
			(options
				(clearance outline)
				(anchor circle)
			)
			(primitives
				(gr_poly
					(pts
						(arc
							(start -0.2032 -0.2794)
							(mid -0.239121 -0.264521)
							(end -0.254 -0.2286)
						)
						(arc
							(start -0.254 0.2286)
							(mid -0.239121 0.264521)
							(end -0.2032 0.2794)
						)
						(arc
							(start 0.2032 0.2794)
							(mid 0.239121 0.264521)
							(end 0.254 0.2286)
						)
						(arc
							(start 0.254 -0.2286)
							(mid 0.239121 -0.264521)
							(end 0.2032 -0.2794)
						)
					)
					(width 0)
					(fill yes)
				)
			)
		)
	)
	(footprint ""
		(layer "F.Cu")
		(at 132.715 -56.388)
		(property "Reference" "PR80"
			(at 0 0 0)
			(layer "F.SilkS")
			(hide yes)
			(effects
				(font
					(size 1.27 1.27)
				)
			)
		)
		(property "Value" "0R3J-0-U-GP"
			(at -0.0254 -2.5146 0)
			(unlocked yes)
			(layer "F.Fab")
			(hide yes)
			(effects
				(font
					(size 1.016 1.016)
					(thickness 0.1524)
				)
			)
		)
		(property "Device Type" "R603H22"
			(at -0.0254 -4.0386 0)
			(unlocked yes)
			(layer "F.Fab")
			(hide yes)
			(effects
				(font
					(size 1.016 1.016)
					(thickness 0.1524)
				)
			)
		)
		(duplicate_pad_numbers_are_jumpers no)
		(fp_line
			(start -0.2032 0)
			(end -0.4191 0)
			(stroke
				(width 0.2032)
				(type default)
			)
			(layer "F.SilkS")
		)
		(fp_line
			(start 0.4318 0)
			(end 0.2032 0)
			(stroke
				(width 0.2032)
				(type default)
			)
			(layer "F.SilkS")
		)
		(fp_rect
			(start -0.635 1.1811)
			(end 0.635 -1.1811)
			(stroke
				(width 0)
				(type default)
			)
			(fill no)
			(layer "F.CrtYd")
		)
		(fp_rect
			(start -0.635 1.1811)
			(end 0.635 -1.1811)
			(stroke
				(width 0)
				(type default)
			)
			(fill no)
			(layer "F.Fab")
		)
		(pad "1" smd custom
			(at 0 -0.6604)
			(size 0.19685 0.19685)
			(layers "F.Cu" "F.Mask" "F.Paste")
			(net "PV_VTT_DDR_A")
			(options
				(clearance outline)
				(anchor circle)
			)
			(primitives
				(gr_poly
					(pts
						(arc
							(start 0.508 -0.2921)
							(mid 0.478242 -0.363942)
							(end 0.4064 -0.3937)
						)
						(arc
							(start -0.4064 -0.3937)
							(mid -0.478242 -0.363942)
							(end -0.508 -0.2921)
						)
						(arc
							(start -0.508 0.2921)
							(mid -0.478242 0.363942)
							(end -0.4064 0.3937)
						)
						(arc
							(start 0.4064 0.3937)
							(mid 0.478242 0.363942)
							(end 0.508 0.2921)
						)
					)
					(width 0)
					(fill yes)
				)
			)
		)
		(pad "2" smd custom
			(at 0 0.6604)
			(size 0.19685 0.19685)
			(layers "F.Cu" "F.Mask" "F.Paste")
			(net "PV_VTT_DDR_SNS")
			(options
				(clearance outline)
				(anchor circle)
			)
			(primitives
				(gr_poly
					(pts
						(arc
							(start 0.508 -0.2921)
							(mid 0.478242 -0.363942)
							(end 0.4064 -0.3937)
						)
						(arc
							(start -0.4064 -0.3937)
							(mid -0.478242 -0.363942)
							(end -0.508 -0.2921)
						)
						(arc
							(start -0.508 0.2921)
							(mid -0.478242 0.363942)
							(end -0.4064 0.3937)
						)
						(arc
							(start 0.4064 0.3937)
							(mid 0.478242 0.363942)
							(end 0.508 0.2921)
						)
					)
					(width 0)
					(fill yes)
				)
			)
		)
	)
	(footprint ""
		(layer "F.Cu")
		(at 111.887 -67.691 180)
		(property "Reference" "U3"
			(at 0 0 180)
			(layer "F.SilkS")
			(hide yes)
			(effects
				(font
					(size 1.27 1.27)
				)
			)
		)
		(property "Value" "2N7002DW-7F-GP"
			(at -2.3622 -8.2042 180)
			(unlocked yes)
			(layer "F.Fab")
			(hide yes)
			(effects
				(font
					(size 1.016 1.016)
					(thickness 0.1524)
				)
			)
		)
		(property "Device Type" "SOT-363H44"
			(at -2.3622 -10.1092 180)
			(unlocked yes)
			(layer "F.Fab")
			(hide yes)
			(effects
				(font
					(size 1.016 1.016)
					(thickness 0.1524)
				)
			)
		)
		(duplicate_pad_numbers_are_jumpers no)
		(fp_poly
			(pts
				(xy -0.6731 1.4351) (xy -0.9779 1.7399) (xy -0.381 1.7399) (xy -0.3683 1.7399) (xy -0.381 1.7272)
			)
			(stroke
				(width 0)
				(type default)
			)
			(fill yes)
			(layer "F.SilkS")
		)
		(fp_poly
			(pts
				(xy 1.2573 0.8763) (xy 1.2573 -0.8763) (xy 0.9525 -0.8763) (xy 0.9525 -1.4351) (xy -0.9525 -1.4351)
				(xy -0.9525 -0.8763) (xy -1.2573 -0.8763) (xy -1.2573 0.8763) (xy -0.9525 0.8763) (xy -0.9525 1.4351)
				(xy 0.9525 1.4351) (xy 0.9525 0.8763)
			)
			(stroke
				(width 0)
				(type default)
			)
			(fill no)
			(layer "F.CrtYd")
		)
		(fp_poly
			(pts
				(xy 1.2573 0.8763) (xy 1.2573 -0.8763) (xy 0.9525 -0.8763) (xy 0.9525 -1.4351) (xy -0.9525 -1.4351)
				(xy -0.9525 -0.8763) (xy -1.2573 -0.8763) (xy -1.2573 0.8763) (xy -0.9525 0.8763) (xy -0.9525 1.4351)
				(xy 0.9525 1.4351) (xy 0.9525 0.8763)
			)
			(stroke
				(width 0)
				(type default)
			)
			(fill no)
			(layer "F.Fab")
		)
		(pad "1" smd rect
			(at -0.65024 0.8255 180)
			(size 0.3556 0.9652)
			(layers "F.Cu" "F.Mask" "F.Paste")
			(net "GND")
		)
		(pad "2" smd rect
			(at 0 0.8255 180)
			(size 0.3556 0.9652)
			(layers "F.Cu" "F.Mask" "F.Paste")
			(net "CLK_GEN_OUT_R")
		)
		(pad "3" smd rect
			(at 0.65024 0.8255 180)
			(size 0.3556 0.9652)
			(layers "F.Cu" "F.Mask" "F.Paste")
			(net "CORE_PWROK")
		)
		(pad "4" smd rect
			(at 0.65024 -0.8255 180)
			(size 0.3556 0.9652)
			(layers "F.Cu" "F.Mask" "F.Paste")
			(net "GND")
		)
		(pad "5" smd rect
			(at 0 -0.8255 180)
			(size 0.3556 0.9652)
			(layers "F.Cu" "F.Mask" "F.Paste")
			(net "CLK_GEN_OUT_R")
		)
		(pad "6" smd rect
			(at -0.65024 -0.8255 180)
			(size 0.3556 0.9652)
			(layers "F.Cu" "F.Mask" "F.Paste")
			(net "PWRGD_DDR3_VCCA")
		)
	)
	(footprint ""
		(layer "F.Cu")
		(at 133.731 -19.431)
		(property "Reference" "R395"
			(at 0 0 0)
			(layer "F.SilkS")
			(hide yes)
			(effects
				(font
					(size 1.27 1.27)
				)
			)
		)
		(property "Value" "0R2J-2-GP"
			(at 1.7907 -1.1176 0)
			(unlocked yes)
			(layer "F.Fab")
			(hide yes)
			(effects
				(font
					(size 1.016 1.016)
					(thickness 0.1524)
				)
			)
		)
		(property "Device Type" "R402H16"
			(at 1.7907 -2.6416 0)
			(unlocked yes)
			(layer "F.Fab")
			(hide yes)
			(effects
				(font
					(size 1.016 1.016)
					(thickness 0.1524)
				)
			)
		)
		(duplicate_pad_numbers_are_jumpers no)
		(fp_rect
			(start -0.381 0.8382)
			(end 0.381 -0.8382)
			(stroke
				(width 0)
				(type default)
			)
			(fill no)
			(layer "F.CrtYd")
		)
		(fp_rect
			(start -0.381 0.8382)
			(end 0.381 -0.8382)
			(stroke
				(width 0)
				(type default)
			)
			(fill no)
			(layer "F.Fab")
		)
		(pad "1" smd custom
			(at 0 -0.4318)
			(size 0.127 0.127)
			(layers "F.Cu" "F.Mask" "F.Paste")
			(net "POWER_GOOD_R")
			(options
				(clearance outline)
				(anchor circle)
			)
			(primitives
				(gr_poly
					(pts
						(arc
							(start -0.2032 -0.2794)
							(mid -0.239121 -0.264521)
							(end -0.254 -0.2286)
						)
						(arc
							(start -0.254 0.2286)
							(mid -0.239121 0.264521)
							(end -0.2032 0.2794)
						)
						(arc
							(start 0.2032 0.2794)
							(mid 0.239121 0.264521)
							(end 0.254 0.2286)
						)
						(arc
							(start 0.254 -0.2286)
							(mid 0.239121 -0.264521)
							(end 0.2032 -0.2794)
						)
					)
					(width 0)
					(fill yes)
				)
			)
		)
		(pad "2" smd custom
			(at 0 0.4318)
			(size 0.127 0.127)
			(layers "F.Cu" "F.Mask" "F.Paste")
			(net "POWER_GOOD")
			(options
				(clearance outline)
				(anchor circle)
			)
			(primitives
				(gr_poly
					(pts
						(arc
							(start -0.2032 -0.2794)
							(mid -0.239121 -0.264521)
							(end -0.254 -0.2286)
						)
						(arc
							(start -0.254 0.2286)
							(mid -0.239121 0.264521)
							(end -0.2032 0.2794)
						)
						(arc
							(start 0.2032 0.2794)
							(mid 0.239121 0.264521)
							(end 0.254 0.2286)
						)
						(arc
							(start 0.254 -0.2286)
							(mid 0.239121 -0.264521)
							(end 0.2032 -0.2794)
						)
					)
					(width 0)
					(fill yes)
				)
			)
		)
	)
	(footprint ""
		(layer "F.Cu")
		(at 61.468 -44.704 180)
		(property "Reference" "C72"
			(at 0 0 180)
			(layer "F.SilkS")
			(hide yes)
			(effects
				(font
					(size 1.27 1.27)
				)
			)
		)
		(property "Value" "SCD1U10V2KX-5GP"
			(at 1.8923 -1.2065 180)
			(unlocked yes)
			(layer "F.Fab")
			(hide yes)
			(effects
				(font
					(size 1.016 1.016)
					(thickness 0.1524)
				)
			)
		)
		(property "Device Type" "C402H22"
			(at 1.8923 -2.7305 180)
			(unlocked yes)
			(layer "F.Fab")
			(hide yes)
			(effects
				(font
					(size 1.016 1.016)
					(thickness 0.1524)
				)
			)
		)
		(duplicate_pad_numbers_are_jumpers no)
		(fp_rect
			(start -0.381 0.7366)
			(end 0.381 -0.7366)
			(stroke
				(width 0)
				(type default)
			)
			(fill no)
			(layer "F.CrtYd")
		)
		(fp_rect
			(start -0.381 0.7366)
			(end 0.381 -0.7366)
			(stroke
				(width 0)
				(type default)
			)
			(fill no)
			(layer "F.Fab")
		)
		(pad "1" smd custom
			(at 0 -0.4572 180)
			(size 0.1143 0.1143)
			(layers "F.Cu" "F.Mask" "F.Paste")
			(net "P3V3_STBY")
			(options
				(clearance outline)
				(anchor circle)
			)
			(primitives
				(gr_poly
					(pts
						(arc
							(start -0.254 -0.1778)
							(mid -0.239121 -0.213721)
							(end -0.2032 -0.2286)
						)
						(arc
							(start 0.2032 -0.2286)
							(mid 0.239121 -0.213721)
							(end 0.254 -0.1778)
						)
						(arc
							(start 0.254 0.1778)
							(mid 0.239121 0.213721)
							(end 0.2032 0.2286)
						)
						(arc
							(start -0.2032 0.2286)
							(mid -0.239121 0.213721)
							(end -0.254 0.1778)
						)
					)
					(width 0)
					(fill yes)
				)
			)
		)
		(pad "2" smd custom
			(at 0 0.4572 180)
			(size 0.1143 0.1143)
			(layers "F.Cu" "F.Mask" "F.Paste")
			(net "GND")
			(options
				(clearance outline)
				(anchor circle)
			)
			(primitives
				(gr_poly
					(pts
						(arc
							(start -0.254 -0.1778)
							(mid -0.239121 -0.213721)
							(end -0.2032 -0.2286)
						)
						(arc
							(start 0.2032 -0.2286)
							(mid 0.239121 -0.213721)
							(end 0.254 -0.1778)
						)
						(arc
							(start 0.254 0.1778)
							(mid 0.239121 0.213721)
							(end 0.2032 0.2286)
						)
						(arc
							(start -0.2032 0.2286)
							(mid -0.239121 0.213721)
							(end -0.254 0.1778)
						)
					)
					(width 0)
					(fill yes)
				)
			)
		)
	)
	(footprint ""
		(layer "F.Cu")
		(at 48.514 -50.165 -90)
		(property "Reference" "C24"
			(at 0 0 270)
			(layer "F.SilkS")
			(hide yes)
			(effects
				(font
					(size 1.27 1.27)
				)
			)
		)
		(property "Value" "SC10U6D3V3MX-GP"
			(at 0 -2.8194 270)
			(unlocked yes)
			(layer "F.Fab")
			(hide yes)
			(effects
				(font
					(size 1.016 1.016)
					(thickness 0.1524)
				)
			)
		)
		(property "Device Type" "C603H38"
			(at 0 -4.3434 270)
			(unlocked yes)
			(layer "F.Fab")
			(hide yes)
			(effects
				(font
					(size 1.016 1.016)
					(thickness 0.1524)
				)
			)
		)
		(duplicate_pad_numbers_are_jumpers no)
		(fp_line
			(start -0.4064 0)
			(end 0.4064 0)
			(stroke
				(width 0.2286)
				(type default)
			)
			(layer "F.SilkS")
		)
		(fp_rect
			(start -0.635 1.1811)
			(end 0.635 -1.1811)
			(stroke
				(width 0)
				(type default)
			)
			(fill no)
			(layer "F.CrtYd")
		)
		(fp_rect
			(start -0.635 1.1811)
			(end 0.635 -1.1811)
			(stroke
				(width 0)
				(type default)
			)
			(fill no)
			(layer "F.Fab")
		)
		(pad "1" smd custom
			(at 0 -0.6604 270)
			(size 0.19685 0.19685)
			(layers "F.Cu" "F.Mask" "F.Paste")
			(net "P1V5_CLK_SCR_LVIO")
			(options
				(clearance outline)
				(anchor circle)
			)
			(primitives
				(gr_poly
					(pts
						(arc
							(start 0.508 -0.2921)
							(mid 0.478242 -0.363942)
							(end 0.4064 -0.3937)
						)
						(arc
							(start -0.4064 -0.3937)
							(mid -0.478242 -0.363942)
							(end -0.508 -0.2921)
						)
						(arc
							(start -0.508 0.2921)
							(mid -0.478242 0.363942)
							(end -0.4064 0.3937)
						)
						(arc
							(start 0.4064 0.3937)
							(mid 0.478242 0.363942)
							(end 0.508 0.2921)
						)
					)
					(width 0)
					(fill yes)
				)
			)
		)
		(pad "2" smd custom
			(at 0 0.6604 270)
			(size 0.19685 0.19685)
			(layers "F.Cu" "F.Mask" "F.Paste")
			(net "GND")
			(options
				(clearance outline)
				(anchor circle)
			)
			(primitives
				(gr_poly
					(pts
						(arc
							(start 0.508 -0.2921)
							(mid 0.478242 -0.363942)
							(end 0.4064 -0.3937)
						)
						(arc
							(start -0.4064 -0.3937)
							(mid -0.478242 -0.363942)
							(end -0.508 -0.2921)
						)
						(arc
							(start -0.508 0.2921)
							(mid -0.478242 0.363942)
							(end -0.4064 0.3937)
						)
						(arc
							(start 0.4064 0.3937)
							(mid 0.478242 0.363942)
							(end 0.508 0.2921)
						)
					)
					(width 0)
					(fill yes)
				)
			)
		)
	)
	(footprint ""
		(layer "F.Cu")
		(at 155.575 -59.309)
		(property "Reference" "C328"
			(at 0 0 0)
			(layer "F.SilkS")
			(hide yes)
			(effects
				(font
					(size 1.27 1.27)
				)
			)
		)
		(property "Value" "SCD1U16V2KX-3GP"
			(at 1.8923 -1.2065 0)
			(unlocked yes)
			(layer "F.Fab")
			(hide yes)
			(effects
				(font
					(size 1.016 1.016)
					(thickness 0.1524)
				)
			)
		)
		(property "Device Type" "C402H22"
			(at 1.8923 -2.7305 0)
			(unlocked yes)
			(layer "F.Fab")
			(hide yes)
			(effects
				(font
					(size 1.016 1.016)
					(thickness 0.1524)
				)
			)
		)
		(duplicate_pad_numbers_are_jumpers no)
		(fp_rect
			(start -0.381 0.7366)
			(end 0.381 -0.7366)
			(stroke
				(width 0)
				(type default)
			)
			(fill no)
			(layer "F.CrtYd")
		)
		(fp_rect
			(start -0.381 0.7366)
			(end 0.381 -0.7366)
			(stroke
				(width 0)
				(type default)
			)
			(fill no)
			(layer "F.Fab")
		)
		(pad "1" smd custom
			(at 0 -0.4572)
			(size 0.1143 0.1143)
			(layers "F.Cu" "F.Mask" "F.Paste")
			(net "PV_VDDR")
			(options
				(clearance outline)
				(anchor circle)
			)
			(primitives
				(gr_poly
					(pts
						(arc
							(start -0.254 -0.1778)
							(mid -0.239121 -0.213721)
							(end -0.2032 -0.2286)
						)
						(arc
							(start 0.2032 -0.2286)
							(mid 0.239121 -0.213721)
							(end 0.254 -0.1778)
						)
						(arc
							(start 0.254 0.1778)
							(mid 0.239121 0.213721)
							(end 0.2032 0.2286)
						)
						(arc
							(start -0.2032 0.2286)
							(mid -0.239121 0.213721)
							(end -0.254 0.1778)
						)
					)
					(width 0)
					(fill yes)
				)
			)
		)
		(pad "2" smd custom
			(at 0 0.4572)
			(size 0.1143 0.1143)
			(layers "F.Cu" "F.Mask" "F.Paste")
			(net "GND")
			(options
				(clearance outline)
				(anchor circle)
			)
			(primitives
				(gr_poly
					(pts
						(arc
							(start -0.254 -0.1778)
							(mid -0.239121 -0.213721)
							(end -0.2032 -0.2286)
						)
						(arc
							(start 0.2032 -0.2286)
							(mid 0.239121 -0.213721)
							(end 0.254 -0.1778)
						)
						(arc
							(start 0.254 0.1778)
							(mid 0.239121 0.213721)
							(end 0.2032 0.2286)
						)
						(arc
							(start -0.2032 0.2286)
							(mid -0.239121 0.213721)
							(end -0.254 0.1778)
						)
					)
					(width 0)
					(fill yes)
				)
			)
		)
	)
)
